# T6G (Grand Teton) — schematic netlist excerpt (pin names and nets, part order shuffled) for the footprints in the layout excerpt that follows; sources: Cadence DE-HDL packaged netlist, KiCad conversion of 04192023_DAF0TMB3IC0_F0TG_MB_C_brd_V02_OCP.brd

R1792  Q_RES  0 5% EMPTY  pkg 0402LF  page 257 : A = SMB_SCM_2_R4_SDA ; B = SMB_SEN_MAM_3V3AUX_SDA
R39  Q_RES  0 5% CHIP  pkg 0402LF  page 131 : A = OCP_SFF_ISO_BIF0_EN ; B = OCP_SFF_BIF0_R_N

(kicad_pcb
	(version 20260206)
	(generator "pcbnew")
	(generator_version "10.0")
	(general
		(thickness 1.6)
		(legacy_teardrops no)
	)
	(paper "A4")
	(title_block
		(title "04192023_DAF0TMB3IC0_F0TG_MB_C_brd_V02_OCP.brd")
		(comment 1 "Grand Teton / footprints 900-901 of 8354")
	)
	(layers
		(0 "F.Cu" signal "TOP")
		(4 "In1.Cu" signal "GND")
		(6 "In2.Cu" signal "IN1")
		(8 "In3.Cu" signal "GND1")
		(10 "In4.Cu" signal "IN2")
		(12 "In5.Cu" signal "GND2")
		(14 "In6.Cu" signal "IN3")
		(16 "In7.Cu" signal "GND3")
		(18 "In8.Cu" signal "VCC")
		(20 "In9.Cu" signal "VCC1")
		(22 "In10.Cu" signal "GND4")
		(24 "In11.Cu" signal "IN4")
		(26 "In12.Cu" signal "GND5")
		(28 "In13.Cu" signal "IN5")
		(30 "In14.Cu" signal "GND6")
		(32 "In15.Cu" signal "IN6")
		(34 "In16.Cu" signal "GND7")
		(2 "B.Cu" signal "BOTTOM")
		(9 "F.Adhes" user "F.Adhesive")
		(11 "B.Adhes" user "B.Adhesive")
		(13 "F.Paste" user "Package Geometry/Pastemask Top")
		(15 "B.Paste" user "Package Geometry/Pastemask Bottom")
		(5 "F.SilkS" user "Ref Des/Silkscreen Top")
		(7 "B.SilkS" user "Ref Des/Silkscreen Bottom")
		(1 "F.Mask" user "Board Geometry/Soldermask Top")
		(3 "B.Mask" user "Board Geometry/Soldermask Bottom")
		(17 "Dwgs.User" user "User.Drawings")
		(19 "Cmts.User" user "User.Comments")
		(21 "Eco1.User" user "User.Eco1")
		(23 "Eco2.User" user "User.Eco2")
		(25 "Edge.Cuts" user "Board Geometry/Outline")
		(27 "Margin" user)
		(31 "F.CrtYd" user "Package Geometry/Place Bound Top")
		(29 "B.CrtYd" user "Package Geometry/Place Bound Bottom")
		(35 "F.Fab" user "Ref Des/Assembly Top")
		(33 "B.Fab" user "Ref Des/Assembly Bottom")
	)
	(footprint ""
		(layer "F.Cu")
		(at 437.221376 -16.244824 -90)
		(property "Reference" "R39"
			(at 0 0 270)
			(layer "F.SilkS")
			(hide yes)
			(effects
				(font
					(size 1.27 1.27)
				)
			)
		)
		(property "Value" ""
			(at 0 0 270)
			(layer "F.Fab")
			(effects
				(font
					(size 1.27 1.27)
				)
			)
		)
		(duplicate_pad_numbers_are_jumpers no)
		(fp_line
			(start -0.7874 0.4064)
			(end -0.7874 -0.4064)
			(stroke
				(width 0.1524)
				(type default)
			)
			(layer "F.SilkS")
		)
		(fp_line
			(start 0.7874 0.4064)
			(end -0.7874 0.4064)
			(stroke
				(width 0.1524)
				(type default)
			)
			(layer "F.SilkS")
		)
		(fp_line
			(start -0.7874 -0.4064)
			(end 0.7874 -0.4064)
			(stroke
				(width 0.1524)
				(type default)
			)
			(layer "F.SilkS")
		)
		(fp_line
			(start 0.7874 -0.4064)
			(end 0.7874 0.4064)
			(stroke
				(width 0.1524)
				(type default)
			)
			(layer "F.SilkS")
		)
		(fp_line
			(start -0.67945 0.3048)
			(end -0.67945 -0.305054)
			(stroke
				(width 0.1)
				(type default)
			)
			(layer "F.Fab")
		)
		(fp_line
			(start -0.12065 0.3048)
			(end -0.67945 0.3048)
			(stroke
				(width 0.1)
				(type default)
			)
			(layer "F.Fab")
		)
		(fp_line
			(start 0.120396 0.3048)
			(end 0.120396 0.2794)
			(stroke
				(width 0.1)
				(type default)
			)
			(layer "F.Fab")
		)
		(fp_line
			(start 0.67945 0.3048)
			(end 0.120396 0.3048)
			(stroke
				(width 0.1)
				(type default)
			)
			(layer "F.Fab")
		)
		(fp_line
			(start -0.12065 0.2794)
			(end -0.12065 0.3048)
			(stroke
				(width 0.1)
				(type default)
			)
			(layer "F.Fab")
		)
		(fp_line
			(start 0.120396 0.2794)
			(end -0.12065 0.2794)
			(stroke
				(width 0.1)
				(type default)
			)
			(layer "F.Fab")
		)
		(fp_line
			(start -0.12065 -0.2794)
			(end 0.12065 -0.2794)
			(stroke
				(width 0.1)
				(type default)
			)
			(layer "F.Fab")
		)
		(fp_line
			(start 0.12065 -0.2794)
			(end 0.12065 -0.3048)
			(stroke
				(width 0.1)
				(type default)
			)
			(layer "F.Fab")
		)
		(fp_line
			(start 0.12065 -0.3048)
			(end 0.67945 -0.3048)
			(stroke
				(width 0.1)
				(type default)
			)
			(layer "F.Fab")
		)
		(fp_line
			(start 0.67945 -0.3048)
			(end 0.67945 0.3048)
			(stroke
				(width 0.1)
				(type default)
			)
			(layer "F.Fab")
		)
		(fp_line
			(start -0.67945 -0.305054)
			(end -0.12065 -0.305054)
			(stroke
				(width 0.1)
				(type default)
			)
			(layer "F.Fab")
		)
		(fp_line
			(start -0.12065 -0.305054)
			(end -0.12065 -0.2794)
			(stroke
				(width 0.1)
				(type default)
			)
			(layer "F.Fab")
		)
		(pad "1" smd circle
			(at -0.40005 0 270)
			(size 0 0)
			(layers "F.Cu" "F.Mask" "F.Paste")
			(net "OCP_SFF_ISO_BIF0_EN")
		)
		(pad "2" smd circle
			(at 0.40005 0 270)
			(size 0 0)
			(layers "F.Cu" "F.Mask" "F.Paste")
			(net "OCP_SFF_BIF0_R_N")
		)
	)
	(footprint ""
		(layer "F.Cu")
		(at 329.360022 -36.001706 180)
		(property "Reference" "R1792"
			(at 0 0 180)
			(layer "F.SilkS")
			(hide yes)
			(effects
				(font
					(size 1.27 1.27)
				)
			)
		)
		(property "Value" ""
			(at 0 0 180)
			(layer "F.Fab")
			(effects
				(font
					(size 1.27 1.27)
				)
			)
		)
		(duplicate_pad_numbers_are_jumpers no)
		(fp_line
			(start 0.7874 0.4064)
			(end -0.7874 0.4064)
			(stroke
				(width 0.1524)
				(type default)
			)
			(layer "F.SilkS")
		)
		(fp_line
			(start 0.7874 -0.4064)
			(end 0.7874 0.4064)
			(stroke
				(width 0.1524)
				(type default)
			)
			(layer "F.SilkS")
		)
		(fp_line
			(start -0.7874 0.4064)
			(end -0.7874 -0.4064)
			(stroke
				(width 0.1524)
				(type default)
			)
			(layer "F.SilkS")
		)
		(fp_line
			(start -0.7874 -0.4064)
			(end 0.7874 -0.4064)
			(stroke
				(width 0.1524)
				(type default)
			)
			(layer "F.SilkS")
		)
		(fp_line
			(start 0.67945 0.3048)
			(end 0.120396 0.3048)
			(stroke
				(width 0.1)
				(type default)
			)
			(layer "F.Fab")
		)
		(fp_line
			(start 0.67945 -0.3048)
			(end 0.67945 0.3048)
			(stroke
				(width 0.1)
				(type default)
			)
			(layer "F.Fab")
		)
		(fp_line
			(start 0.12065 -0.2794)
			(end 0.12065 -0.3048)
			(stroke
				(width 0.1)
				(type default)
			)
			(layer "F.Fab")
		)
		(fp_line
			(start 0.12065 -0.3048)
			(end 0.67945 -0.3048)
			(stroke
				(width 0.1)
				(type default)
			)
			(layer "F.Fab")
		)
		(fp_line
			(start 0.120396 0.3048)
			(end 0.120396 0.2794)
			(stroke
				(width 0.1)
				(type default)
			)
			(layer "F.Fab")
		)
		(fp_line
			(start 0.120396 0.2794)
			(end -0.12065 0.2794)
			(stroke
				(width 0.1)
				(type default)
			)
			(layer "F.Fab")
		)
		(fp_line
			(start -0.12065 0.3048)
			(end -0.67945 0.3048)
			(stroke
				(width 0.1)
				(type default)
			)
			(layer "F.Fab")
		)
		(fp_line
			(start -0.12065 0.2794)
			(end -0.12065 0.3048)
			(stroke
				(width 0.1)
				(type default)
			)
			(layer "F.Fab")
		)
		(fp_line
			(start -0.12065 -0.2794)
			(end 0.12065 -0.2794)
			(stroke
				(width 0.1)
				(type default)
			)
			(layer "F.Fab")
		)
		(fp_line
			(start -0.12065 -0.305054)
			(end -0.12065 -0.2794)
			(stroke
				(width 0.1)
				(type default)
			)
			(layer "F.Fab")
		)
		(fp_line
			(start -0.67945 0.3048)
			(end -0.67945 -0.305054)
			(stroke
				(width 0.1)
				(type default)
			)
			(layer "F.Fab")
		)
		(fp_line
			(start -0.67945 -0.305054)
			(end -0.12065 -0.305054)
			(stroke
				(width 0.1)
				(type default)
			)
			(layer "F.Fab")
		)
		(pad "1" smd circle
			(at -0.40005 0 180)
			(size 0 0)
			(layers "F.Cu" "F.Mask" "F.Paste")
			(net "SMB_SCM_2_R4_SDA")
		)
		(pad "2" smd circle
			(at 0.40005 0 180)
			(size 0 0)
			(layers "F.Cu" "F.Mask" "F.Paste")
			(net "SMB_SEN_MAM_3V3AUX_SDA")
		)
	)
)
